(kicad_pcb
	(version 20260206)
	(generator "pcbnew")
	(generator_version "10.0")
	(general
		(thickness 1.6)
		(legacy_teardrops no)
	)
	(paper "A4")
	(title_block
		(title "03242023_DA0F0TMBIJ0_F0T_Motherboard_J_brd_V01_OCP.brd")
		(comment 1 "Grand Teton / footprint 2359 of 6105 (J45), pads 1-62 of 62")
	)
	(layers
		(0 "F.Cu" signal "TOP")
		(4 "In1.Cu" signal "GND")
		(6 "In2.Cu" signal "IN1")
		(8 "In3.Cu" signal "GND1")
		(10 "In4.Cu" signal "IN2")
		(12 "In5.Cu" signal "GND2")
		(14 "In6.Cu" signal "IN3")
		(16 "In7.Cu" signal "GND3")
		(18 "In8.Cu" signal "VCC")
		(20 "In9.Cu" signal "VCC1")
		(22 "In10.Cu" signal "GND4")
		(24 "In11.Cu" signal "IN4")
		(26 "In12.Cu" signal "GND5")
		(28 "In13.Cu" signal "IN5")
		(30 "In14.Cu" signal "GND6")
		(32 "In15.Cu" signal "IN6")
		(34 "In16.Cu" signal "GND7")
		(2 "B.Cu" signal "BOTTOM")
		(9 "F.Adhes" user "F.Adhesive")
		(11 "B.Adhes" user "B.Adhesive")
		(13 "F.Paste" user "Package Geometry/Pastemask Top")
		(15 "B.Paste" user "Package Geometry/Pastemask Bottom")
		(5 "F.SilkS" user "Ref Des/Silkscreen Top")
		(7 "B.SilkS" user "Ref Des/Silkscreen Bottom")
		(1 "F.Mask" user "Board Geometry/Soldermask Top")
		(3 "B.Mask" user "Board Geometry/Soldermask Bottom")
		(17 "Dwgs.User" user "User.Drawings")
		(19 "Cmts.User" user "User.Comments")
		(21 "Eco1.User" user "User.Eco1")
		(23 "Eco2.User" user "User.Eco2")
		(25 "Edge.Cuts" user "Board Geometry/Outline")
		(27 "Margin" user)
		(31 "F.CrtYd" user "Package Geometry/Place Bound Top")
		(29 "B.CrtYd" user "Package Geometry/Place Bound Bottom")
		(35 "F.Fab" user "Ref Des/Assembly Top")
		(33 "B.Fab" user "Ref Des/Assembly Bottom")
	)
	(footprint ""
		(layer "F.Cu")
		(at 238.45012 -435.58206 -90)
		(property "Reference" "J45"
			(at 7.573772 -37.93236 0)
			(unlocked yes)
			(layer "F.SilkS")
			(effects
				(font
					(size 0.7874 0.5842)
					(thickness 0.1524)
				)
				(justify left)
			)
		)
		(property "Value" ""
			(at 0 0 270)
			(layer "F.Fab")
			(effects
				(font
					(size 1.27 1.27)
				)
			)
		)
		(duplicate_pad_numbers_are_jumpers no)
		(pad "" np_thru_hole circle
			(at 2.54 -32.385 270)
			(size 0 0)
			(drill 3.048)
			(layers "*.Cu" "*.Mask")
			(clearance 0)
		)
		(pad "" np_thru_hole circle
			(at 2.54 37.465 270)
			(size 0 0)
			(drill 3.048)
			(layers "*.Cu" "*.Mask")
			(clearance 0)
		)
		(pad "A1" thru_hole rect
			(at 0 0 270)
			(size 1.669796 1.669796)
			(drill 1.01981)
			(layers "*.Cu" "*.Mask")
			(remove_unused_layers no)
			(net "TP_J45_A1")
			(clearance -0.070866)
			(padstack
				(mode front_inner_back)
				(layer "Inner"
					(shape circle)
					(size 1.669796 1.669796)
					(clearance -0.070866)
				)
				(layer "B.Cu"
					(shape rect)
					(size 1.669796 1.669796)
					(clearance -0.070866)
				)
			)
		)
		(pad "A2" thru_hole circle
			(at 0 2.54 270)
			(size 1.669796 1.669796)
			(drill 1.01981)
			(layers "*.Cu" "*.Mask")
			(remove_unused_layers no)
			(net "FM_AC_PWR_BTN_PDB_N")
			(clearance -0.070866)
		)
		(pad "A3" thru_hole circle
			(at 0 5.08 270)
			(size 1.669796 1.669796)
			(drill 1.01981)
			(layers "*.Cu" "*.Mask")
			(remove_unused_layers no)
			(net "P3V3_PDB_AUX_ADC")
			(clearance -0.070866)
		)
		(pad "B1" thru_hole circle
			(at 2.54 0 270)
			(size 1.669796 1.669796)
			(drill 1.01981)
			(layers "*.Cu" "*.Mask")
			(remove_unused_layers no)
			(net "RST_SMB_SWITCH_R_N")
			(clearance -0.070866)
		)
		(pad "B2" thru_hole circle
			(at 2.54 2.54 270)
			(size 1.669796 1.669796)
			(drill 1.01981)
			(layers "*.Cu" "*.Mask")
			(remove_unused_layers no)
			(net "PWRGD_P3V3_AUX_PDB_BUF")
			(clearance -0.070866)
		)
		(pad "B3" thru_hole circle
			(at 2.54 5.08 270)
			(size 1.669796 1.669796)
			(drill 1.01981)
			(layers "*.Cu" "*.Mask")
			(remove_unused_layers no)
			(net "GND")
			(clearance -0.070866)
		)
		(pad "C1" thru_hole circle
			(at 5.08 0 270)
			(size 1.669796 1.669796)
			(drill 1.01981)
			(layers "*.Cu" "*.Mask")
			(remove_unused_layers no)
			(net "SMB_FAN_3V3AUX_BUF_R_SCL")
			(clearance -0.070866)
		)
		(pad "C2" thru_hole circle
			(at 5.08 2.54 270)
			(size 1.669796 1.669796)
			(drill 1.01981)
			(layers "*.Cu" "*.Mask")
			(remove_unused_layers no)
			(net "SMB_FAN_3V3AUX_BUF_R_SDA")
			(clearance -0.070866)
		)
		(pad "C3" thru_hole circle
			(at 5.08 5.08 270)
			(size 1.669796 1.669796)
			(drill 1.01981)
			(layers "*.Cu" "*.Mask")
			(remove_unused_layers no)
			(net "HPDB_HSC_PWRGD_R")
			(clearance -0.070866)
		)
		(pad "D1" thru_hole circle
			(at 7.62 0 270)
			(size 1.669796 1.669796)
			(drill 1.01981)
			(layers "*.Cu" "*.Mask")
			(remove_unused_layers no)
			(net "FM_FAN_PWR_EN_R")
			(clearance -0.070866)
		)
		(pad "D2" thru_hole circle
			(at 7.62 2.54 270)
			(size 1.669796 1.669796)
			(drill 1.01981)
			(layers "*.Cu" "*.Mask")
			(remove_unused_layers no)
			(net "FM_GPU_HSC_EN_BUF_R1")
			(clearance -0.070866)
		)
		(pad "D3" thru_hole circle
			(at 7.62 5.08 270)
			(size 1.669796 1.669796)
			(drill 1.01981)
			(layers "*.Cu" "*.Mask")
			(remove_unused_layers no)
			(net "PDB_PRSNT_N")
			(clearance -0.070866)
		)
		(pad "P1_1" thru_hole circle
			(at 0 -25.4 270)
			(size 1.669796 1.669796)
			(drill 1.01981)
			(layers "*.Cu" "*.Mask")
			(remove_unused_layers no)
			(net "GND")
			(clearance -0.070866)
		)
		(pad "P1_2" thru_hole circle
			(at 2.54 -25.4 270)
			(size 1.669796 1.669796)
			(drill 1.01981)
			(layers "*.Cu" "*.Mask")
			(remove_unused_layers no)
			(net "GND")
			(clearance -0.070866)
		)
		(pad "P1_3" thru_hole circle
			(at 5.08 -25.4 270)
			(size 1.669796 1.669796)
			(drill 1.01981)
			(layers "*.Cu" "*.Mask")
			(remove_unused_layers no)
			(net "GND")
			(clearance -0.070866)
		)
		(pad "P1_4" thru_hole circle
			(at 7.62 -25.4 270)
			(size 1.669796 1.669796)
			(drill 1.01981)
			(layers "*.Cu" "*.Mask")
			(remove_unused_layers no)
			(net "GND")
			(clearance -0.070866)
		)
		(pad "P1_5" thru_hole circle
			(at 0 -22.86 270)
			(size 1.669796 1.669796)
			(drill 1.01981)
			(layers "*.Cu" "*.Mask")
			(remove_unused_layers no)
			(net "GND")
			(clearance -0.070866)
		)
		(pad "P1_6" thru_hole circle
			(at 2.54 -22.86 270)
			(size 1.669796 1.669796)
			(drill 1.01981)
			(layers "*.Cu" "*.Mask")
			(remove_unused_layers no)
			(net "GND")
			(clearance -0.070866)
		)
		(pad "P1_7" thru_hole circle
			(at 5.08 -22.86 270)
			(size 1.669796 1.669796)
			(drill 1.01981)
			(layers "*.Cu" "*.Mask")
			(remove_unused_layers no)
			(net "GND")
			(clearance -0.070866)
		)
		(pad "P1_8" thru_hole circle
			(at 7.62 -22.86 270)
			(size 1.669796 1.669796)
			(drill 1.01981)
			(layers "*.Cu" "*.Mask")
			(remove_unused_layers no)
			(net "GND")
			(clearance -0.070866)
		)
		(pad "P2_1" thru_hole circle
			(at 0 -16.51 270)
			(size 1.669796 1.669796)
			(drill 1.01981)
			(layers "*.Cu" "*.Mask")
			(remove_unused_layers no)
			(net "GND")
			(clearance -0.070866)
		)
		(pad "P2_2" thru_hole circle
			(at 2.54 -16.51 270)
			(size 1.669796 1.669796)
			(drill 1.01981)
			(layers "*.Cu" "*.Mask")
			(remove_unused_layers no)
			(net "GND")
			(clearance -0.070866)
		)
		(pad "P2_3" thru_hole circle
			(at 5.08 -16.51 270)
			(size 1.669796 1.669796)
			(drill 1.01981)
			(layers "*.Cu" "*.Mask")
			(remove_unused_layers no)
			(net "GND")
			(clearance -0.070866)
		)
		(pad "P2_4" thru_hole circle
			(at 7.62 -16.51 270)
			(size 1.669796 1.669796)
			(drill 1.01981)
			(layers "*.Cu" "*.Mask")
			(remove_unused_layers no)
			(net "GND")
			(clearance -0.070866)
		)
		(pad "P2_5" thru_hole circle
			(at 0 -13.97 270)
			(size 1.669796 1.669796)
			(drill 1.01981)
			(layers "*.Cu" "*.Mask")
			(remove_unused_layers no)
			(net "GND")
			(clearance -0.070866)
		)
		(pad "P2_6" thru_hole circle
			(at 2.54 -13.97 270)
			(size 1.669796 1.669796)
			(drill 1.01981)
			(layers "*.Cu" "*.Mask")
			(remove_unused_layers no)
			(net "GND")
			(clearance -0.070866)
		)
		(pad "P2_7" thru_hole circle
			(at 5.08 -13.97 270)
			(size 1.669796 1.669796)
			(drill 1.01981)
			(layers "*.Cu" "*.Mask")
			(remove_unused_layers no)
			(net "GND")
			(clearance -0.070866)
		)
		(pad "P2_8" thru_hole circle
			(at 7.62 -13.97 270)
			(size 1.669796 1.669796)
			(drill 1.01981)
			(layers "*.Cu" "*.Mask")
			(remove_unused_layers no)
			(net "GND")
			(clearance -0.070866)
		)
		(pad "P3_1" thru_hole circle
			(at 0 -7.62 270)
			(size 1.669796 1.669796)
			(drill 1.01981)
			(layers "*.Cu" "*.Mask")
			(remove_unused_layers no)
			(net "GND")
			(clearance -0.070866)
		)
		(pad "P3_2" thru_hole circle
			(at 2.54 -7.62 270)
			(size 1.669796 1.669796)
			(drill 1.01981)
			(layers "*.Cu" "*.Mask")
			(remove_unused_layers no)
			(net "GND")
			(clearance -0.070866)
		)
		(pad "P3_3" thru_hole circle
			(at 5.08 -7.62 270)
			(size 1.669796 1.669796)
			(drill 1.01981)
			(layers "*.Cu" "*.Mask")
			(remove_unused_layers no)
			(net "GND")
			(clearance -0.070866)
		)
		(pad "P3_4" thru_hole circle
			(at 7.62 -7.62 270)
			(size 1.669796 1.669796)
			(drill 1.01981)
			(layers "*.Cu" "*.Mask")
			(remove_unused_layers no)
			(net "GND")
			(clearance -0.070866)
		)
		(pad "P3_5" thru_hole circle
			(at 0 -5.08 270)
			(size 1.669796 1.669796)
			(drill 1.01981)
			(layers "*.Cu" "*.Mask")
			(remove_unused_layers no)
			(net "GND")
			(clearance -0.070866)
		)
		(pad "P3_6" thru_hole circle
			(at 2.54 -5.08 270)
			(size 1.669796 1.669796)
			(drill 1.01981)
			(layers "*.Cu" "*.Mask")
			(remove_unused_layers no)
			(net "GND")
			(clearance -0.070866)
		)
		(pad "P3_7" thru_hole circle
			(at 5.08 -5.08 270)
			(size 1.669796 1.669796)
			(drill 1.01981)
			(layers "*.Cu" "*.Mask")
			(remove_unused_layers no)
			(net "GND")
			(clearance -0.070866)
		)
		(pad "P3_8" thru_hole circle
			(at 7.62 -5.08 270)
			(size 1.669796 1.669796)
			(drill 1.01981)
			(layers "*.Cu" "*.Mask")
			(remove_unused_layers no)
			(net "GND")
			(clearance -0.070866)
		)
		(pad "P4_1" thru_hole circle
			(at 0 10.16 270)
			(size 1.669796 1.669796)
			(drill 1.01981)
			(layers "*.Cu" "*.Mask")
			(remove_unused_layers no)
			(net "P12V_PSU")
			(clearance -0.070866)
		)
		(pad "P4_2" thru_hole circle
			(at 2.54 10.16 270)
			(size 1.669796 1.669796)
			(drill 1.01981)
			(layers "*.Cu" "*.Mask")
			(remove_unused_layers no)
			(net "P12V_PSU")
			(clearance -0.070866)
		)
		(pad "P4_3" thru_hole circle
			(at 5.08 10.16 270)
			(size 1.669796 1.669796)
			(drill 1.01981)
			(layers "*.Cu" "*.Mask")
			(remove_unused_layers no)
			(net "P12V_PSU")
			(clearance -0.070866)
		)
		(pad "P4_4" thru_hole circle
			(at 7.62 10.16 270)
			(size 1.669796 1.669796)
			(drill 1.01981)
			(layers "*.Cu" "*.Mask")
			(remove_unused_layers no)
			(net "P12V_PSU")
			(clearance -0.070866)
		)
		(pad "P4_5" thru_hole circle
			(at 0 12.7 270)
			(size 1.669796 1.669796)
			(drill 1.01981)
			(layers "*.Cu" "*.Mask")
			(remove_unused_layers no)
			(net "P12V_PSU")
			(clearance -0.070866)
		)
		(pad "P4_6" thru_hole circle
			(at 2.54 12.7 270)
			(size 1.669796 1.669796)
			(drill 1.01981)
			(layers "*.Cu" "*.Mask")
			(remove_unused_layers no)
			(net "P12V_PSU")
			(clearance -0.070866)
		)
		(pad "P4_7" thru_hole circle
			(at 5.08 12.7 270)
			(size 1.669796 1.669796)
			(drill 1.01981)
			(layers "*.Cu" "*.Mask")
			(remove_unused_layers no)
			(net "P12V_PSU")
			(clearance -0.070866)
		)
		(pad "P4_8" thru_hole circle
			(at 7.62 12.7 270)
			(size 1.669796 1.669796)
			(drill 1.01981)
			(layers "*.Cu" "*.Mask")
			(remove_unused_layers no)
			(net "P12V_PSU")
			(clearance -0.070866)
		)
		(pad "P5_1" thru_hole circle
			(at 0 19.05 270)
			(size 1.669796 1.669796)
			(drill 1.01981)
			(layers "*.Cu" "*.Mask")
			(remove_unused_layers no)
			(net "P12V_PSU")
			(clearance -0.070866)
		)
		(pad "P5_2" thru_hole circle
			(at 2.54 19.05 270)
			(size 1.669796 1.669796)
			(drill 1.01981)
			(layers "*.Cu" "*.Mask")
			(remove_unused_layers no)
			(net "P12V_PSU")
			(clearance -0.070866)
		)
		(pad "P5_3" thru_hole circle
			(at 5.08 19.05 270)
			(size 1.669796 1.669796)
			(drill 1.01981)
			(layers "*.Cu" "*.Mask")
			(remove_unused_layers no)
			(net "P12V_PSU")
			(clearance -0.070866)
		)
		(pad "P5_4" thru_hole circle
			(at 7.62 19.05 270)
			(size 1.669796 1.669796)
			(drill 1.01981)
			(layers "*.Cu" "*.Mask")
			(remove_unused_layers no)
			(net "P12V_PSU")
			(clearance -0.070866)
		)
		(pad "P5_5" thru_hole circle
			(at 0 21.59 270)
			(size 1.669796 1.669796)
			(drill 1.01981)
			(layers "*.Cu" "*.Mask")
			(remove_unused_layers no)
			(net "P12V_PSU")
			(clearance -0.070866)
		)
		(pad "P5_6" thru_hole circle
			(at 2.54 21.59 270)
			(size 1.669796 1.669796)
			(drill 1.01981)
			(layers "*.Cu" "*.Mask")
			(remove_unused_layers no)
			(net "P12V_PSU")
			(clearance -0.070866)
		)
		(pad "P5_7" thru_hole circle
			(at 5.08 21.59 270)
			(size 1.669796 1.669796)
			(drill 1.01981)
			(layers "*.Cu" "*.Mask")
			(remove_unused_layers no)
			(net "P12V_PSU")
			(clearance -0.070866)
		)
		(pad "P5_8" thru_hole circle
			(at 7.62 21.59 270)
			(size 1.669796 1.669796)
			(drill 1.01981)
			(layers "*.Cu" "*.Mask")
			(remove_unused_layers no)
			(net "P12V_PSU")
			(clearance -0.070866)
		)
		(pad "P6_1" thru_hole circle
			(at 0 27.94 270)
			(size 1.669796 1.669796)
			(drill 1.01981)
			(layers "*.Cu" "*.Mask")
			(remove_unused_layers no)
			(net "P12V_PSU")
			(clearance -0.070866)
		)
		(pad "P6_2" thru_hole circle
			(at 2.54 27.94 270)
			(size 1.669796 1.669796)
			(drill 1.01981)
			(layers "*.Cu" "*.Mask")
			(remove_unused_layers no)
			(net "P12V_PSU")
			(clearance -0.070866)
		)
		(pad "P6_3" thru_hole circle
			(at 5.08 27.94 270)
			(size 1.669796 1.669796)
			(drill 1.01981)
			(layers "*.Cu" "*.Mask")
			(remove_unused_layers no)
			(net "P12V_PSU")
			(clearance -0.070866)
		)
		(pad "P6_4" thru_hole circle
			(at 7.62 27.94 270)
			(size 1.669796 1.669796)
			(drill 1.01981)
			(layers "*.Cu" "*.Mask")
			(remove_unused_layers no)
			(net "P12V_PSU")
			(clearance -0.070866)
		)
		(pad "P6_5" thru_hole circle
			(at 0 30.48 270)
			(size 1.669796 1.669796)
			(drill 1.01981)
			(layers "*.Cu" "*.Mask")
			(remove_unused_layers no)
			(net "P12V_PSU")
			(clearance -0.070866)
		)
		(pad "P6_6" thru_hole circle
			(at 2.54 30.48 270)
			(size 1.669796 1.669796)
			(drill 1.01981)
			(layers "*.Cu" "*.Mask")
			(remove_unused_layers no)
			(net "P12V_PSU")
			(clearance -0.070866)
		)
		(pad "P6_7" thru_hole circle
			(at 5.08 30.48 270)
			(size 1.669796 1.669796)
			(drill 1.01981)
			(layers "*.Cu" "*.Mask")
			(remove_unused_layers no)
			(net "P12V_PSU")
			(clearance -0.070866)
		)
		(pad "P6_8" thru_hole circle
			(at 7.62 30.48 270)
			(size 1.669796 1.669796)
			(drill 1.01981)
			(layers "*.Cu" "*.Mask")
			(remove_unused_layers no)
			(net "P12V_PSU")
			(clearance -0.070866)
		)
	)
)
